# ZAIUS-LV CARD-DVT-X01-BOM-X00_20170420_Final.xls.xlsx — Changelist (bom)
| BOM Change List Date:Thu Apr 20 13:53:09 GMT+08:00 2017 |  |  |  |  |  |  |  |  |  |
| New BOM file : C:\<user>\ZAIUS-LV CARD-DVT-X01-BOM-X00_20170420_Final.xls |  |  |  |  |  |  |  |  |  |
| Old BOM file : C:\<user>\ZAIUS-LV CARD-DVT-X01-BOM-X00_20170419_Final.xls |  |  |  |  |  |  |  |  |  |
| ##### Add Parts |  |  |  |  |  |  |  |  |  |
| Item | Location | Qty | Foxconn P/N | Part Description | Manufacturer Full Name | Manufacturer P/N | RoHS | Sheet |  |
| 1 | PCB | 1 | 0101EW900-000-G | PCB,Zaius-LV Card DVT-X01,OSP,Blu,4L,1.5925*0.9953,G | GOLD CIRCUIT ELECTRONICS LTD. | 0101EW900-000-G |  | PWA BOM |  |
| ##### Remove Parts |  |  |  |  |  |  |  |  |  |
| Item | Location | Qty | Foxconn P/N | Part Description | Manufacturer Full Name | Manufacturer P/N | RoHS | Sheet |  |
| ##### Change Parts |  |  |  |  |  |  |  |  |  |
| Item | Location | Qty | Foxconn P/N | Part Description | Manufacturer Full Name | Manufacturer P/N | RoHS | Sheet | Remark |
| ##### Change Revision |  |  |  |  |  |  |  |  |  |
| Sheet | REV OF BOM | CUSTOMER | CUSTOMER P/N | PWA PN | PWA DESCRIPTION | PWA REV | DATE | Remark |  |
| OOOOOOOOOOOOOOOOOOOOOOOOOOOOOOOOOOOOOOOOOOOOOOOOOOOOOOOOOOOOOOOOOOOOOOOOOOOOOOOOOOOOOOOOOO | OOOOOOOOOOOOOOOOOOOOOOOOOOOOOOOOOOOOOOOOOOOOOOOOOOOOOOOOOOOOOOOOOOOOOOOOOOOOOOOOOOOOOOOOOO | OOOOOOOOOOOOOOOOOOOOOOOOOOOOOOOOOOOOOOOOOOOOOOOOOOOOOOOOOOOOOOOOOOOOOOOOOOOOOOOOOOOOOOOOOO | OOOOOOOOOOOOOOOOOOOOOOOOOOOOOOOOOOOOOOOOOOOOOOOOOOOOOOOOOOOOOOOOOOOOOOOOOOOOOOOOOOOOOOOOOO | OOOOOOOOOOOOOOOOOOOOOOOOOOOOOOOOOOOOOOOOOOOOOOOOOOOOOOOOOOOOOOOOOOOOOOOOOOOOOOOOOOOOOOOOOO | OOOOOOOOOOOOOOOOOOOOOOOOOOOOOOOOOOOOOOOOOOOOOOOOOOOOOOOOOOOOOOOOOOOOOOOOOOOOOOOOOOOOOOOOOO | OOOOOOOOOOOOOOOOOOOOOOOOOOOOOOOOOOOOOOOOOOOOOOOOOOOOOOOOOOOOOOOOOOOOOOOOOOOOOOOOOOOOOOOOOO | OOOOOOOOOOOOOOOOOOOOOOOOOOOOOOOOOOOOOOOOOOOOOOOOOOOOOOOOOOOOOOOOOOOOOOOOOOOOOOOOOOOOOOOOOO | OOOOOOOOOOOOOOOOOOOOOOOOOOOOOOOOOOOOOOOOOOOOOOOOOOOOOOOOOOOOOOOOOOOOOOOOOOOOOOOOOOOOOOOOOO | OOOOOOOOOOOOOOOOOOOOOOOOOOOOOOOOOOOOOOOOOOOOOOOOOOOOOOOOOOOOOOOOOOOOOOOOOOOOOOOOOOOOOOOOOO |
| Second Source Change |  |  |  |  |  |  |  |  |  |
| Item | Location | Change Type | Foxconn P/N | Part Description | Manufacturer Full Name | Manufacturer P/N | RoHS | Sheet |  |
| OOOOOOOOOOOOOOOOOOOOOOOOOOOOOOOOOOOOOOOOOOOOOOOOOOOOOOOOOOOOOOOOOOOOOOOOOOOOOOOOOOOOOOOOOO | OOOOOOOOOOOOOOOOOOOOOOOOOOOOOOOOOOOOOOOOOOOOOOOOOOOOOOOOOOOOOOOOOOOOOOOOOOOOOOOOOOOOOOOOOO | OOOOOOOOOOOOOOOOOOOOOOOOOOOOOOOOOOOOOOOOOOOOOOOOOOOOOOOOOOOOOOOOOOOOOOOOOOOOOOOOOOOOOOOOOO | OOOOOOOOOOOOOOOOOOOOOOOOOOOOOOOOOOOOOOOOOOOOOOOOOOOOOOOOOOOOOOOOOOOOOOOOOOOOOOOOOOOOOOOOOO | OOOOOOOOOOOOOOOOOOOOOOOOOOOOOOOOOOOOOOOOOOOOOOOOOOOOOOOOOOOOOOOOOOOOOOOOOOOOOOOOOOOOOOOOOO | OOOOOOOOOOOOOOOOOOOOOOOOOOOOOOOOOOOOOOOOOOOOOOOOOOOOOOOOOOOOOOOOOOOOOOOOOOOOOOOOOOOOOOOOOO | OOOOOOOOOOOOOOOOOOOOOOOOOOOOOOOOOOOOOOOOOOOOOOOOOOOOOOOOOOOOOOOOOOOOOOOOOOOOOOOOOOOOOOOOOO | OOOOOOOOOOOOOOOOOOOOOOOOOOOOOOOOOOOOOOOOOOOOOOOOOOOOOOOOOOOOOOOOOOOOOOOOOOOOOOOOOOOOOOOOOO | OOOOOOOOOOOOOOOOOOOOOOOOOOOOOOOOOOOOOOOOOOOOOOOOOOOOOOOOOOOOOOOOOOOOOOOOOOOOOOOOOOOOOOOOOO | OOOOOOOOOOOOOOOOOOOOOOOOOOOOOOOOOOOOOOOOOOOOOOOOOOOOOOOOOOOOOOOOOOOOOOOOOOOOOOOOOOOOOOOOOO |
| Master Materials Change |  |  |  |  |  |  |  |  |  |
| Item | Foxconn P/N | Orig._Usage | New_Usage | Part Description | Manufacturer Full Name | Manufacturer P/N | RoHS | Location | Sheet |
| 1 | 0101EW900-000-G | 0 | 1 | PCB,Zaius-LV Card DVT-X01,OSP,Blu,4L,1.5925*0.9953,G | GOLD CIRCUIT ELECTRONICS LTD. | 0101EW900-000-G |  | (+)PCB | PWA BOM |
| OOOOOOOOOOOOOOOOOOOOOOOOOOOOOOOOOOOOOOOOOOOOOOOOOOOOOOOOOOOOOOOOOOOOOOOOOOOOOOOOOOOOOOOOOO | OOOOOOOOOOOOOOOOOOOOOOOOOOOOOOOOOOOOOOOOOOOOOOOOOOOOOOOOOOOOOOOOOOOOOOOOOOOOOOOOOOOOOOOOOO | OOOOOOOOOOOOOOOOOOOOOOOOOOOOOOOOOOOOOOOOOOOOOOOOOOOOOOOOOOOOOOOOOOOOOOOOOOOOOOOOOOOOOOOOOO | OOOOOOOOOOOOOOOOOOOOOOOOOOOOOOOOOOOOOOOOOOOOOOOOOOOOOOOOOOOOOOOOOOOOOOOOOOOOOOOOOOOOOOOOOO | OOOOOOOOOOOOOOOOOOOOOOOOOOOOOOOOOOOOOOOOOOOOOOOOOOOOOOOOOOOOOOOOOOOOOOOOOOOOOOOOOOOOOOOOOO | OOOOOOOOOOOOOOOOOOOOOOOOOOOOOOOOOOOOOOOOOOOOOOOOOOOOOOOOOOOOOOOOOOOOOOOOOOOOOOOOOOOOOOOOOO | OOOOOOOOOOOOOOOOOOOOOOOOOOOOOOOOOOOOOOOOOOOOOOOOOOOOOOOOOOOOOOOOOOOOOOOOOOOOOOOOOOOOOOOOOO | OOOOOOOOOOOOOOOOOOOOOOOOOOOOOOOOOOOOOOOOOOOOOOOOOOOOOOOOOOOOOOOOOOOOOOOOOOOOOOOOOOOOOOOOOO | OOOOOOOOOOOOOOOOOOOOOOOOOOOOOOOOOOOOOOOOOOOOOOOOOOOOOOOOOOOOOOOOOOOOOOOOOOOOOOOOOOOOOOOOOO | OOOOOOOOOOOOOOOOOOOOOOOOOOOOOOOOOOOOOOOOOOOOOOOOOOOOOOOOOOOOOOOOOOOOOOOOOOOOOOOOOOOOOOOOOO |
| TLA Parts Change |  |  |  |  |  |  |  |  |  |
| Item | Foxconn P/N | Qty | Part Description | Manufacturer Full Name | Manufacturer P/N | RoHS | Location | Remark | BOM |
